(kicad_pcb
	(version 20260206)
	(generator "pcbnew")
	(generator_version "10.0")
	(general
		(thickness 1.6)
		(legacy_teardrops no)
	)
	(paper "A4")
	(title_block
		(title "03242023_DA0F0TMBIJ0_F0T_Motherboard_J_brd_V01_OCP.brd")
		(comment 1 "Grand Teton / footprints 4105-4110 of 6105")
	)
	(layers
		(0 "F.Cu" signal "TOP")
		(4 "In1.Cu" signal "GND")
		(6 "In2.Cu" signal "IN1")
		(8 "In3.Cu" signal "GND1")
		(10 "In4.Cu" signal "IN2")
		(12 "In5.Cu" signal "GND2")
		(14 "In6.Cu" signal "IN3")
		(16 "In7.Cu" signal "GND3")
		(18 "In8.Cu" signal "VCC")
		(20 "In9.Cu" signal "VCC1")
		(22 "In10.Cu" signal "GND4")
		(24 "In11.Cu" signal "IN4")
		(26 "In12.Cu" signal "GND5")
		(28 "In13.Cu" signal "IN5")
		(30 "In14.Cu" signal "GND6")
		(32 "In15.Cu" signal "IN6")
		(34 "In16.Cu" signal "GND7")
		(2 "B.Cu" signal "BOTTOM")
		(9 "F.Adhes" user "F.Adhesive")
		(11 "B.Adhes" user "B.Adhesive")
		(13 "F.Paste" user "Package Geometry/Pastemask Top")
		(15 "B.Paste" user "Package Geometry/Pastemask Bottom")
		(5 "F.SilkS" user "Ref Des/Silkscreen Top")
		(7 "B.SilkS" user "Ref Des/Silkscreen Bottom")
		(1 "F.Mask" user "Board Geometry/Soldermask Top")
		(3 "B.Mask" user "Board Geometry/Soldermask Bottom")
		(17 "Dwgs.User" user "User.Drawings")
		(19 "Cmts.User" user "User.Comments")
		(21 "Eco1.User" user "User.Eco1")
		(23 "Eco2.User" user "User.Eco2")
		(25 "Edge.Cuts" user "Board Geometry/Outline")
		(27 "Margin" user)
		(31 "F.CrtYd" user "Package Geometry/Place Bound Top")
		(29 "B.CrtYd" user "Package Geometry/Place Bound Bottom")
		(35 "F.Fab" user "Ref Des/Assembly Top")
		(33 "B.Fab" user "Ref Des/Assembly Bottom")
	)
	(footprint ""
		(layer "F.Cu")
		(at 432.41468 -175.69942)
		(property "Reference" "PR501"
			(at 0 0 0)
			(layer "F.SilkS")
			(hide yes)
			(effects
				(font
					(size 1.27 1.27)
				)
			)
		)
		(property "Value" ""
			(at 0 0 0)
			(layer "F.Fab")
			(effects
				(font
					(size 1.27 1.27)
				)
			)
		)
		(duplicate_pad_numbers_are_jumpers no)
		(fp_line
			(start -0.7874 -0.4064)
			(end 0.7874 -0.4064)
			(stroke
				(width 0.1524)
				(type default)
			)
			(layer "F.SilkS")
		)
		(fp_line
			(start -0.7874 0.4064)
			(end -0.7874 -0.4064)
			(stroke
				(width 0.1524)
				(type default)
			)
			(layer "F.SilkS")
		)
		(fp_line
			(start 0.7874 -0.4064)
			(end 0.7874 0.4064)
			(stroke
				(width 0.1524)
				(type default)
			)
			(layer "F.SilkS")
		)
		(fp_line
			(start 0.7874 0.4064)
			(end -0.7874 0.4064)
			(stroke
				(width 0.1524)
				(type default)
			)
			(layer "F.SilkS")
		)
		(fp_line
			(start -0.67945 -0.305054)
			(end -0.12065 -0.305054)
			(stroke
				(width 0.1)
				(type default)
			)
			(layer "F.Fab")
		)
		(fp_line
			(start -0.67945 0.3048)
			(end -0.67945 -0.305054)
			(stroke
				(width 0.1)
				(type default)
			)
			(layer "F.Fab")
		)
		(fp_line
			(start -0.12065 -0.305054)
			(end -0.12065 -0.2794)
			(stroke
				(width 0.1)
				(type default)
			)
			(layer "F.Fab")
		)
		(fp_line
			(start -0.12065 -0.2794)
			(end 0.12065 -0.2794)
			(stroke
				(width 0.1)
				(type default)
			)
			(layer "F.Fab")
		)
		(fp_line
			(start -0.12065 0.2794)
			(end -0.12065 0.3048)
			(stroke
				(width 0.1)
				(type default)
			)
			(layer "F.Fab")
		)
		(fp_line
			(start -0.12065 0.3048)
			(end -0.67945 0.3048)
			(stroke
				(width 0.1)
				(type default)
			)
			(layer "F.Fab")
		)
		(fp_line
			(start 0.120396 0.2794)
			(end -0.12065 0.2794)
			(stroke
				(width 0.1)
				(type default)
			)
			(layer "F.Fab")
		)
		(fp_line
			(start 0.120396 0.3048)
			(end 0.120396 0.2794)
			(stroke
				(width 0.1)
				(type default)
			)
			(layer "F.Fab")
		)
		(fp_line
			(start 0.12065 -0.3048)
			(end 0.67945 -0.3048)
			(stroke
				(width 0.1)
				(type default)
			)
			(layer "F.Fab")
		)
		(fp_line
			(start 0.12065 -0.2794)
			(end 0.12065 -0.3048)
			(stroke
				(width 0.1)
				(type default)
			)
			(layer "F.Fab")
		)
		(fp_line
			(start 0.67945 -0.3048)
			(end 0.67945 0.3048)
			(stroke
				(width 0.1)
				(type default)
			)
			(layer "F.Fab")
		)
		(fp_line
			(start 0.67945 0.3048)
			(end 0.120396 0.3048)
			(stroke
				(width 0.1)
				(type default)
			)
			(layer "F.Fab")
		)
		(pad "1" smd circle
			(at -0.40005 0)
			(size 0 0)
			(layers "F.Cu" "F.Mask" "F.Paste")
			(net "PVNN_MAIN_CPU0_FB")
		)
		(pad "2" smd circle
			(at 0.40005 0)
			(size 0 0)
			(layers "F.Cu" "F.Mask" "F.Paste")
			(net "PVNN_MAIN_CPU0_FB_RC")
		)
	)
	(footprint ""
		(layer "F.Cu")
		(at 193.93408 -357.139748)
		(property "Reference" "R1005"
			(at 0 0 0)
			(layer "F.SilkS")
			(hide yes)
			(effects
				(font
					(size 1.27 1.27)
				)
			)
		)
		(property "Value" ""
			(at 0 0 0)
			(layer "F.Fab")
			(effects
				(font
					(size 1.27 1.27)
				)
			)
		)
		(duplicate_pad_numbers_are_jumpers no)
		(fp_line
			(start -0.7874 -0.4064)
			(end 0.7874 -0.4064)
			(stroke
				(width 0.1524)
				(type default)
			)
			(layer "F.SilkS")
		)
		(fp_line
			(start -0.7874 0.4064)
			(end -0.7874 -0.4064)
			(stroke
				(width 0.1524)
				(type default)
			)
			(layer "F.SilkS")
		)
		(fp_line
			(start 0.7874 -0.4064)
			(end 0.7874 0.4064)
			(stroke
				(width 0.1524)
				(type default)
			)
			(layer "F.SilkS")
		)
		(fp_line
			(start 0.7874 0.4064)
			(end -0.7874 0.4064)
			(stroke
				(width 0.1524)
				(type default)
			)
			(layer "F.SilkS")
		)
		(fp_line
			(start -0.67945 -0.305054)
			(end -0.12065 -0.305054)
			(stroke
				(width 0.1)
				(type default)
			)
			(layer "F.Fab")
		)
		(fp_line
			(start -0.67945 0.3048)
			(end -0.67945 -0.305054)
			(stroke
				(width 0.1)
				(type default)
			)
			(layer "F.Fab")
		)
		(fp_line
			(start -0.12065 -0.305054)
			(end -0.12065 -0.2794)
			(stroke
				(width 0.1)
				(type default)
			)
			(layer "F.Fab")
		)
		(fp_line
			(start -0.12065 -0.2794)
			(end 0.12065 -0.2794)
			(stroke
				(width 0.1)
				(type default)
			)
			(layer "F.Fab")
		)
		(fp_line
			(start -0.12065 0.2794)
			(end -0.12065 0.3048)
			(stroke
				(width 0.1)
				(type default)
			)
			(layer "F.Fab")
		)
		(fp_line
			(start -0.12065 0.3048)
			(end -0.67945 0.3048)
			(stroke
				(width 0.1)
				(type default)
			)
			(layer "F.Fab")
		)
		(fp_line
			(start 0.120396 0.2794)
			(end -0.12065 0.2794)
			(stroke
				(width 0.1)
				(type default)
			)
			(layer "F.Fab")
		)
		(fp_line
			(start 0.120396 0.3048)
			(end 0.120396 0.2794)
			(stroke
				(width 0.1)
				(type default)
			)
			(layer "F.Fab")
		)
		(fp_line
			(start 0.12065 -0.3048)
			(end 0.67945 -0.3048)
			(stroke
				(width 0.1)
				(type default)
			)
			(layer "F.Fab")
		)
		(fp_line
			(start 0.12065 -0.2794)
			(end 0.12065 -0.3048)
			(stroke
				(width 0.1)
				(type default)
			)
			(layer "F.Fab")
		)
		(fp_line
			(start 0.67945 -0.3048)
			(end 0.67945 0.3048)
			(stroke
				(width 0.1)
				(type default)
			)
			(layer "F.Fab")
		)
		(fp_line
			(start 0.67945 0.3048)
			(end 0.120396 0.3048)
			(stroke
				(width 0.1)
				(type default)
			)
			(layer "F.Fab")
		)
		(pad "1" smd circle
			(at -0.40005 0)
			(size 0 0)
			(layers "F.Cu" "F.Mask" "F.Paste")
			(net "PU_PIROM_CPU1_SM_WP")
		)
		(pad "2" smd circle
			(at 0.40005 0)
			(size 0 0)
			(layers "F.Cu" "F.Mask" "F.Paste")
			(net "GND")
		)
	)
	(footprint ""
		(layer "F.Cu")
		(at 446.73393 -181.983888)
		(property "Reference" "PC1278"
			(at 0 0 0)
			(layer "F.SilkS")
			(hide yes)
			(effects
				(font
					(size 1.27 1.27)
				)
			)
		)
		(property "Value" ""
			(at 0 0 0)
			(layer "F.Fab")
			(effects
				(font
					(size 1.27 1.27)
				)
			)
		)
		(duplicate_pad_numbers_are_jumpers no)
		(fp_line
			(start -1.524 -0.762)
			(end 1.524 -0.762)
			(stroke
				(width 0.1524)
				(type default)
			)
			(layer "F.SilkS")
		)
		(fp_line
			(start -1.524 0.762)
			(end -1.524 -0.762)
			(stroke
				(width 0.1524)
				(type default)
			)
			(layer "F.SilkS")
		)
		(fp_line
			(start 1.524 -0.762)
			(end 1.524 0.762)
			(stroke
				(width 0.1524)
				(type default)
			)
			(layer "F.SilkS")
		)
		(fp_line
			(start 1.524 0.762)
			(end -1.524 0.762)
			(stroke
				(width 0.1524)
				(type default)
			)
			(layer "F.SilkS")
		)
		(fp_line
			(start -1.1049 -0.724916)
			(end -1.1049 0.724916)
			(stroke
				(width 0.1)
				(type default)
			)
			(layer "F.Fab")
		)
		(fp_line
			(start -1.1049 0.724916)
			(end 1.1049 0.724916)
			(stroke
				(width 0.1)
				(type default)
			)
			(layer "F.Fab")
		)
		(fp_line
			(start 1.1049 -0.724916)
			(end -1.1049 -0.724916)
			(stroke
				(width 0.1)
				(type default)
			)
			(layer "F.Fab")
		)
		(fp_line
			(start 1.1049 0.724916)
			(end 1.1049 -0.724916)
			(stroke
				(width 0.1)
				(type default)
			)
			(layer "F.Fab")
		)
		(pad "1" smd rect
			(at -0.889 0 180)
			(size 1.016 1.27)
			(layers "F.Cu" "F.Mask" "F.Paste")
			(net "PVNN_MAIN_CPU0")
		)
		(pad "2" smd rect
			(at 0.889 0 180)
			(size 1.016 1.27)
			(layers "F.Cu" "F.Mask" "F.Paste")
			(net "GND")
		)
	)
	(footprint ""
		(layer "F.Cu")
		(at 28.578048 -71.88073)
		(property "Reference" "C1810"
			(at 0 0 0)
			(layer "F.SilkS")
			(hide yes)
			(effects
				(font
					(size 1.27 1.27)
				)
			)
		)
		(property "Value" ""
			(at 0 0 0)
			(layer "F.Fab")
			(effects
				(font
					(size 1.27 1.27)
				)
			)
		)
		(duplicate_pad_numbers_are_jumpers no)
		(fp_line
			(start -0.7874 -0.4064)
			(end 0.7874 -0.4064)
			(stroke
				(width 0.1524)
				(type default)
			)
			(layer "F.SilkS")
		)
		(fp_line
			(start -0.7874 0.4064)
			(end -0.7874 -0.4064)
			(stroke
				(width 0.1524)
				(type default)
			)
			(layer "F.SilkS")
		)
		(fp_line
			(start 0.7874 -0.4064)
			(end 0.7874 0.4064)
			(stroke
				(width 0.1524)
				(type default)
			)
			(layer "F.SilkS")
		)
		(fp_line
			(start 0.7874 0.4064)
			(end -0.7874 0.4064)
			(stroke
				(width 0.1524)
				(type default)
			)
			(layer "F.SilkS")
		)
		(fp_line
			(start -0.67945 -0.305054)
			(end -0.12065 -0.305054)
			(stroke
				(width 0.1)
				(type default)
			)
			(layer "F.Fab")
		)
		(fp_line
			(start -0.67945 0.3048)
			(end -0.67945 -0.305054)
			(stroke
				(width 0.1)
				(type default)
			)
			(layer "F.Fab")
		)
		(fp_line
			(start -0.12065 -0.305054)
			(end -0.12065 -0.2794)
			(stroke
				(width 0.1)
				(type default)
			)
			(layer "F.Fab")
		)
		(fp_line
			(start -0.12065 -0.2794)
			(end 0.12065 -0.2794)
			(stroke
				(width 0.1)
				(type default)
			)
			(layer "F.Fab")
		)
		(fp_line
			(start -0.12065 0.2794)
			(end -0.12065 0.3048)
			(stroke
				(width 0.1)
				(type default)
			)
			(layer "F.Fab")
		)
		(fp_line
			(start -0.12065 0.3048)
			(end -0.67945 0.3048)
			(stroke
				(width 0.1)
				(type default)
			)
			(layer "F.Fab")
		)
		(fp_line
			(start 0.120396 0.2794)
			(end -0.12065 0.2794)
			(stroke
				(width 0.1)
				(type default)
			)
			(layer "F.Fab")
		)
		(fp_line
			(start 0.120396 0.3048)
			(end 0.120396 0.2794)
			(stroke
				(width 0.1)
				(type default)
			)
			(layer "F.Fab")
		)
		(fp_line
			(start 0.12065 -0.3048)
			(end 0.67945 -0.3048)
			(stroke
				(width 0.1)
				(type default)
			)
			(layer "F.Fab")
		)
		(fp_line
			(start 0.12065 -0.2794)
			(end 0.12065 -0.3048)
			(stroke
				(width 0.1)
				(type default)
			)
			(layer "F.Fab")
		)
		(fp_line
			(start 0.67945 -0.3048)
			(end 0.67945 0.3048)
			(stroke
				(width 0.1)
				(type default)
			)
			(layer "F.Fab")
		)
		(fp_line
			(start 0.67945 0.3048)
			(end 0.120396 0.3048)
			(stroke
				(width 0.1)
				(type default)
			)
			(layer "F.Fab")
		)
		(pad "1" smd circle
			(at -0.40005 0)
			(size 0 0)
			(layers "F.Cu" "F.Mask" "F.Paste")
			(net "P3V3_AUX")
		)
		(pad "2" smd circle
			(at 0.40005 0)
			(size 0 0)
			(layers "F.Cu" "F.Mask" "F.Paste")
			(net "GND")
		)
	)
	(footprint ""
		(layer "F.Cu")
		(at 284.62732 -408.53868)
		(property "Reference" "R4893"
			(at 0 0 0)
			(layer "F.SilkS")
			(hide yes)
			(effects
				(font
					(size 1.27 1.27)
				)
			)
		)
		(property "Value" ""
			(at 0 0 0)
			(layer "F.Fab")
			(effects
				(font
					(size 1.27 1.27)
				)
			)
		)
		(duplicate_pad_numbers_are_jumpers no)
		(fp_line
			(start -0.7874 -0.4064)
			(end 0.7874 -0.4064)
			(stroke
				(width 0.1524)
				(type default)
			)
			(layer "F.SilkS")
		)
		(fp_line
			(start -0.7874 0.4064)
			(end -0.7874 -0.4064)
			(stroke
				(width 0.1524)
				(type default)
			)
			(layer "F.SilkS")
		)
		(fp_line
			(start 0.7874 -0.4064)
			(end 0.7874 0.4064)
			(stroke
				(width 0.1524)
				(type default)
			)
			(layer "F.SilkS")
		)
		(fp_line
			(start 0.7874 0.4064)
			(end -0.7874 0.4064)
			(stroke
				(width 0.1524)
				(type default)
			)
			(layer "F.SilkS")
		)
		(fp_line
			(start -0.67945 -0.305054)
			(end -0.12065 -0.305054)
			(stroke
				(width 0.1)
				(type default)
			)
			(layer "F.Fab")
		)
		(fp_line
			(start -0.67945 0.3048)
			(end -0.67945 -0.305054)
			(stroke
				(width 0.1)
				(type default)
			)
			(layer "F.Fab")
		)
		(fp_line
			(start -0.12065 -0.305054)
			(end -0.12065 -0.2794)
			(stroke
				(width 0.1)
				(type default)
			)
			(layer "F.Fab")
		)
		(fp_line
			(start -0.12065 -0.2794)
			(end 0.12065 -0.2794)
			(stroke
				(width 0.1)
				(type default)
			)
			(layer "F.Fab")
		)
		(fp_line
			(start -0.12065 0.2794)
			(end -0.12065 0.3048)
			(stroke
				(width 0.1)
				(type default)
			)
			(layer "F.Fab")
		)
		(fp_line
			(start -0.12065 0.3048)
			(end -0.67945 0.3048)
			(stroke
				(width 0.1)
				(type default)
			)
			(layer "F.Fab")
		)
		(fp_line
			(start 0.120396 0.2794)
			(end -0.12065 0.2794)
			(stroke
				(width 0.1)
				(type default)
			)
			(layer "F.Fab")
		)
		(fp_line
			(start 0.120396 0.3048)
			(end 0.120396 0.2794)
			(stroke
				(width 0.1)
				(type default)
			)
			(layer "F.Fab")
		)
		(fp_line
			(start 0.12065 -0.3048)
			(end 0.67945 -0.3048)
			(stroke
				(width 0.1)
				(type default)
			)
			(layer "F.Fab")
		)
		(fp_line
			(start 0.12065 -0.2794)
			(end 0.12065 -0.3048)
			(stroke
				(width 0.1)
				(type default)
			)
			(layer "F.Fab")
		)
		(fp_line
			(start 0.67945 -0.3048)
			(end 0.67945 0.3048)
			(stroke
				(width 0.1)
				(type default)
			)
			(layer "F.Fab")
		)
		(fp_line
			(start 0.67945 0.3048)
			(end 0.120396 0.3048)
			(stroke
				(width 0.1)
				(type default)
			)
			(layer "F.Fab")
		)
		(pad "1" smd circle
			(at -0.40005 0)
			(size 0 0)
			(layers "F.Cu" "F.Mask" "F.Paste")
			(net "P12V_HSC_TEMP_E")
		)
		(pad "2" smd circle
			(at 0.40005 0)
			(size 0 0)
			(layers "F.Cu" "F.Mask" "F.Paste")
			(net "P12V_HSC_TEMP_D-")
		)
	)
	(footprint ""
		(layer "F.Cu")
		(at 216.18575 -43.738292 180)
		(property "Reference" "U279"
			(at -0.69977 -3.434334 0)
			(unlocked yes)
			(layer "F.SilkS")
			(effects
				(font
					(size 0.7874 0.5842)
					(thickness 0.1524)
				)
				(justify left)
			)
		)
		(property "Value" ""
			(at 0 0 180)
			(layer "F.Fab")
			(effects
				(font
					(size 1.27 1.27)
				)
			)
		)
		(duplicate_pad_numbers_are_jumpers no)
		(fp_line
			(start 1.463548 1.549908)
			(end -1.463548 1.549908)
			(stroke
				(width 0.1524)
				(type default)
			)
			(layer "F.SilkS")
		)
		(fp_line
			(start 1.463548 -1.549908)
			(end 1.463548 1.549908)
			(stroke
				(width 0.1524)
				(type default)
			)
			(layer "F.SilkS")
		)
		(fp_line
			(start 0.762 -1.549908)
			(end 1.463548 -1.549908)
			(stroke
				(width 0.1524)
				(type default)
			)
			(layer "F.SilkS")
		)
		(fp_line
			(start 0 -0.762)
			(end 0.762 -1.549908)
			(stroke
				(width 0.1524)
				(type default)
			)
			(layer "F.SilkS")
		)
		(fp_line
			(start -0.787908 -1.549908)
			(end 0 -0.762)
			(stroke
				(width 0.1524)
				(type default)
			)
			(layer "F.SilkS")
		)
		(fp_line
			(start -1.463548 1.549908)
			(end -1.463548 -1.549908)
			(stroke
				(width 0.1524)
				(type default)
			)
			(layer "F.SilkS")
		)
		(fp_line
			(start -1.463548 -1.549908)
			(end -0.787908 -1.549908)
			(stroke
				(width 0.1524)
				(type default)
			)
			(layer "F.SilkS")
		)
		(fp_poly
			(pts
				(xy -2.86004 -1.050036) (xy -3.4798 -0.740156) (xy -3.4798 -1.359916)
			)
			(stroke
				(width 0)
				(type default)
			)
			(fill yes)
			(layer "F.SilkS")
		)
		(fp_line
			(start 1.549908 1.549908)
			(end -1.549908 1.549908)
			(stroke
				(width 0.1)
				(type default)
			)
			(layer "F.Fab")
		)
		(fp_line
			(start 1.549908 -1.549908)
			(end 1.549908 1.549908)
			(stroke
				(width 0.1)
				(type default)
			)
			(layer "F.Fab")
		)
		(fp_line
			(start -1.549908 1.549908)
			(end -1.549908 -1.549908)
			(stroke
				(width 0.1)
				(type default)
			)
			(layer "F.Fab")
		)
		(fp_line
			(start -1.549908 -1.549908)
			(end 1.549908 -1.549908)
			(stroke
				(width 0.1)
				(type default)
			)
			(layer "F.Fab")
		)
		(fp_poly
			(pts
				(xy -3.4798 -1.359916) (xy -2.86004 -1.050036) (xy -3.4798 -0.740156)
			)
			(stroke
				(width 0)
				(type default)
			)
			(fill yes)
			(layer "F.Fab")
		)
		(pad "1" smd rect
			(at -2.175002 -1.050036 270)
			(size 0.6096 1.1684)
			(layers "F.Cu" "F.Mask" "F.Paste")
			(net "P3V3_E1S_0")
		)
		(pad "2" smd rect
			(at -2.175002 -0.32512 270)
			(size 0.4318 1.1684)
			(layers "F.Cu" "F.Mask" "F.Paste")
			(net "SMB_E1S_3V3AUX_ISO_SCL_R")
		)
		(pad "3" smd rect
			(at -2.175002 0.32512 270)
			(size 0.4318 1.1684)
			(layers "F.Cu" "F.Mask" "F.Paste")
			(net "SMB_E1S_3V3AUX_ISO_SDA_R")
		)
		(pad "4" smd rect
			(at -2.175002 1.050036 270)
			(size 0.6096 1.1684)
			(layers "F.Cu" "F.Mask" "F.Paste")
			(net "GND")
		)
		(pad "5" smd rect
			(at 2.175002 1.050036 270)
			(size 0.6096 1.1684)
			(layers "F.Cu" "F.Mask" "F.Paste")
			(net "SMB_PCIE_E1S_ISO_EN_R")
		)
		(pad "6" smd rect
			(at 2.175002 0.32512 270)
			(size 0.4318 1.1684)
			(layers "F.Cu" "F.Mask" "F.Paste")
			(net "SMB_SENSOR_E1S_3V3AUX_SDA")
		)
		(pad "7" smd rect
			(at 2.175002 -0.32512 270)
			(size 0.4318 1.1684)
			(layers "F.Cu" "F.Mask" "F.Paste")
			(net "SMB_SENSOR_E1S_3V3AUX_SCL")
		)
		(pad "8" smd rect
			(at 2.175002 -1.050036 270)
			(size 0.6096 1.1684)
			(layers "F.Cu" "F.Mask" "F.Paste")
			(net "P3V3_AUX")
		)
	)
)
